(kicad_pcb
	(version 20260206)
	(generator "pcbnew")
	(generator_version "10.0")
	(general
		(thickness 1.6)
		(legacy_teardrops no)
	)
	(paper "A4")
	(title_block
		(title "Wiwynn_Tioga_Pass_MB.brd")
		(comment 1 "Tioga Pass / footprints 2587-2593 of 4770")
	)
	(layers
		(0 "F.Cu" signal "TOP")
		(4 "In1.Cu" signal "L2GND")
		(6 "In2.Cu" signal "L3")
		(8 "In3.Cu" signal "L4GND")
		(10 "In4.Cu" signal "L5")
		(12 "In5.Cu" signal "L6GND")
		(14 "In6.Cu" signal "L7VCC")
		(16 "In7.Cu" signal "L8VCC")
		(18 "In8.Cu" signal "L9GND")
		(20 "In9.Cu" signal "L10")
		(22 "In10.Cu" signal "L11GND")
		(24 "In11.Cu" signal "L12")
		(26 "In12.Cu" signal "L13GND")
		(2 "B.Cu" signal "BOTTOM")
		(9 "F.Adhes" user "F.Adhesive")
		(11 "B.Adhes" user "B.Adhesive")
		(13 "F.Paste" user "Package Geometry/Pastemask Top")
		(15 "B.Paste" user "Package Geometry/Pastemask Bottom")
		(5 "F.SilkS" user "Ref Des/Silkscreen Top")
		(7 "B.SilkS" user "Ref Des/Silkscreen Bottom")
		(1 "F.Mask" user "Board Geometry/Soldermask Top")
		(3 "B.Mask" user "Board Geometry/Soldermask Bottom")
		(17 "Dwgs.User" user "User.Drawings")
		(19 "Cmts.User" user "User.Comments")
		(21 "Eco1.User" user "User.Eco1")
		(23 "Eco2.User" user "User.Eco2")
		(25 "Edge.Cuts" user "Board Geometry/Outline")
		(27 "Margin" user)
		(31 "F.CrtYd" user "Package Geometry/Place Bound Top")
		(29 "B.CrtYd" user "Package Geometry/Place Bound Bottom")
		(35 "F.Fab" user "Ref Des/Assembly Top")
		(33 "B.Fab" user "Ref Des/Assembly Bottom")
	)
	(footprint ""
		(layer "B.Cu")
		(at 108.178854 -77.82814)
		(property "Reference" "C7P10"
			(at 0 0 0)
			(layer "B.SilkS")
			(hide yes)
			(effects
				(font
					(size 1.27 1.27)
				)
				(justify mirror)
			)
		)
		(property "Value" ""
			(at 0 0 0)
			(layer "B.Fab")
			(effects
				(font
					(size 1.27 1.27)
				)
				(justify mirror)
			)
		)
		(duplicate_pad_numbers_are_jumpers no)
		(fp_poly
			(pts
				(xy 0.7239 -0.2159) (xy -0.7239 -0.2159) (xy -0.7239 1.9939) (xy 0.7239 1.9939)
			)
			(stroke
				(width 0)
				(type default)
			)
			(fill no)
			(layer "B.CrtYd")
		)
		(fp_line
			(start -0.7239 -0.2159)
			(end 0.7239 -0.2159)
			(stroke
				(width 0.1)
				(type default)
			)
			(layer "B.Fab")
		)
		(fp_line
			(start -0.7239 1.9939)
			(end -0.7239 -0.2159)
			(stroke
				(width 0.1)
				(type default)
			)
			(layer "B.Fab")
		)
		(fp_line
			(start 0.7239 -0.2159)
			(end 0.7239 1.9939)
			(stroke
				(width 0.1)
				(type default)
			)
			(layer "B.Fab")
		)
		(fp_line
			(start 0.7239 1.9939)
			(end -0.7239 1.9939)
			(stroke
				(width 0.1)
				(type default)
			)
			(layer "B.Fab")
		)
		(pad "1" smd rect
			(at 0 0 180)
			(size 1.27 1.016)
			(layers "B.Cu" "B.Mask" "B.Paste")
			(net "PVCCMCP_CPU1")
		)
		(pad "2" smd rect
			(at 0 1.778 180)
			(size 1.27 1.016)
			(layers "B.Cu" "B.Mask" "B.Paste")
			(net "GND")
		)
		(zone
			(layer "B.Cu")
			(hatch none 0.5)
			(connect_pads
				(clearance 0)
			)
			(min_thickness 0.25)
			(keepout
				(tracks not_allowed)
				(vias allowed)
				(pads allowed)
				(copperpour not_allowed)
				(footprints allowed)
			)
			(placement
				(enabled no)
				(sheetname "")
			)
			(fill
				(thermal_gap 0.5)
				(thermal_bridge_width 0.5)
				(island_removal_mode 0)
			)
			(polygon
				(pts
					(xy 108.813854 -77.32014) (xy 107.543854 -77.32014) (xy 107.543854 -76.55814) (xy 108.813854 -76.55814)
				)
			)
		)
	)
	(footprint ""
		(layer "B.Cu")
		(at 474.85046 -27.29992 180)
		(property "Reference" "R2T23"
			(at 0 0 0)
			(layer "B.SilkS")
			(hide yes)
			(effects
				(font
					(size 1.27 1.27)
				)
				(justify mirror)
			)
		)
		(property "Value" ""
			(at 0 0 0)
			(layer "B.Fab")
			(effects
				(font
					(size 1.27 1.27)
				)
				(justify mirror)
			)
		)
		(duplicate_pad_numbers_are_jumpers no)
		(fp_poly
			(pts
				(xy 0.4953 -0.2032) (xy -0.4953 -0.2032) (xy -0.4953 1.6002) (xy 0.4953 1.6002)
			)
			(stroke
				(width 0)
				(type default)
			)
			(fill no)
			(layer "B.CrtYd")
		)
		(fp_line
			(start 0.4953 1.6002)
			(end 0.4953 -0.2032)
			(stroke
				(width 0.1)
				(type default)
			)
			(layer "B.Fab")
		)
		(fp_line
			(start 0.4953 -0.2032)
			(end -0.4953 -0.2032)
			(stroke
				(width 0.1)
				(type default)
			)
			(layer "B.Fab")
		)
		(fp_line
			(start -0.4953 1.6002)
			(end 0.4953 1.6002)
			(stroke
				(width 0.1)
				(type default)
			)
			(layer "B.Fab")
		)
		(fp_line
			(start -0.4953 -0.2032)
			(end -0.4953 1.6002)
			(stroke
				(width 0.1)
				(type default)
			)
			(layer "B.Fab")
		)
		(pad "1" smd rect
			(at 0 0)
			(size 0.762 0.889)
			(layers "B.Cu" "B.Mask" "B.Paste")
			(net "P3V3_STBY_MNG")
		)
		(pad "2" smd rect
			(at 0 1.397)
			(size 0.762 0.889)
			(layers "B.Cu" "B.Mask" "B.Paste")
			(net "P3V3_STBY_MNG_RGMII")
		)
		(zone
			(layer "B.Cu")
			(hatch none 0.5)
			(connect_pads
				(clearance 0)
			)
			(min_thickness 0.25)
			(keepout
				(tracks not_allowed)
				(vias allowed)
				(pads allowed)
				(copperpour not_allowed)
				(footprints allowed)
			)
			(placement
				(enabled no)
				(sheetname "")
			)
			(fill
				(thermal_gap 0.5)
				(thermal_bridge_width 0.5)
				(island_removal_mode 0)
			)
			(polygon
				(pts
					(xy 474.46946 -28.25242) (xy 474.46946 -27.74442) (xy 475.23146 -27.74442) (xy 475.23146 -28.25242)
				)
			)
		)
		(zone
			(layer "B.Cu")
			(hatch none 0.5)
			(connect_pads
				(clearance 0)
			)
			(min_thickness 0.25)
			(keepout
				(tracks allowed)
				(vias not_allowed)
				(pads allowed)
				(copperpour not_allowed)
				(footprints allowed)
			)
			(placement
				(enabled no)
				(sheetname "")
			)
			(fill
				(thermal_gap 0.5)
				(thermal_bridge_width 0.5)
				(island_removal_mode 0)
			)
			(polygon
				(pts
					(xy 475.23146 -28.25242) (xy 475.23146 -27.74442) (xy 474.46946 -27.74442) (xy 474.46946 -28.25242)
				)
			)
		)
	)
	(footprint ""
		(layer "B.Cu")
		(at 488.696 -18.161 -90)
		(property "Reference" "R1R3"
			(at 0.8382 -0.67818 270)
			(unlocked yes)
			(layer "B.SilkS")
			(effects
				(font
					(size 0.4064 0.254)
					(thickness 0.1524)
				)
				(justify left mirror)
			)
		)
		(property "Value" ""
			(at 0 0 90)
			(layer "B.Fab")
			(effects
				(font
					(size 1.27 1.27)
				)
				(justify mirror)
			)
		)
		(duplicate_pad_numbers_are_jumpers no)
		(fp_poly
			(pts
				(xy 0.2794 -0.1016) (xy -0.2794 -0.1016) (xy -0.2794 0.9906) (xy 0.2794 0.9906)
			)
			(stroke
				(width 0)
				(type default)
			)
			(fill no)
			(layer "B.CrtYd")
		)
		(fp_line
			(start -0.2794 0.9906)
			(end -0.2794 -0.1016)
			(stroke
				(width 0.1)
				(type default)
			)
			(layer "B.Fab")
		)
		(fp_line
			(start 0.2794 0.9906)
			(end -0.2794 0.9906)
			(stroke
				(width 0.1)
				(type default)
			)
			(layer "B.Fab")
		)
		(fp_line
			(start -0.2794 -0.1016)
			(end 0.2794 -0.1016)
			(stroke
				(width 0.1)
				(type default)
			)
			(layer "B.Fab")
		)
		(fp_line
			(start 0.2794 -0.1016)
			(end 0.2794 0.9906)
			(stroke
				(width 0.1)
				(type default)
			)
			(layer "B.Fab")
		)
		(pad "1" smd rect
			(at 0 0 90)
			(size 0.508 0.508)
			(layers "B.Cu" "B.Mask" "B.Paste")
			(net "P3V3_STBY")
		)
		(pad "2" smd rect
			(at 0 0.889 90)
			(size 0.508 0.508)
			(layers "B.Cu" "B.Mask" "B.Paste")
			(net "PU_NV_WP_N")
		)
		(zone
			(layer "B.Cu")
			(hatch none 0.5)
			(connect_pads
				(clearance 0)
			)
			(min_thickness 0.25)
			(keepout
				(tracks not_allowed)
				(vias allowed)
				(pads allowed)
				(copperpour not_allowed)
				(footprints allowed)
			)
			(placement
				(enabled no)
				(sheetname "")
			)
			(fill
				(thermal_gap 0.5)
				(thermal_bridge_width 0.5)
				(island_removal_mode 0)
			)
			(polygon
				(pts
					(xy 488.061 -17.907) (xy 488.061 -18.415) (xy 488.442 -18.415) (xy 488.442 -17.907)
				)
			)
		)
		(zone
			(layer "B.Cu")
			(hatch none 0.5)
			(connect_pads
				(clearance 0)
			)
			(min_thickness 0.25)
			(keepout
				(tracks allowed)
				(vias not_allowed)
				(pads allowed)
				(copperpour not_allowed)
				(footprints allowed)
			)
			(placement
				(enabled no)
				(sheetname "")
			)
			(fill
				(thermal_gap 0.5)
				(thermal_bridge_width 0.5)
				(island_removal_mode 0)
			)
			(polygon
				(pts
					(xy 488.442 -17.907) (xy 488.442 -18.415) (xy 488.061 -18.415) (xy 488.061 -17.907)
				)
			)
		)
	)
	(footprint ""
		(layer "B.Cu")
		(at 388.0104 -125.507242 -90)
		(property "Reference" "R3M12"
			(at 0 0 90)
			(layer "B.SilkS")
			(hide yes)
			(effects
				(font
					(size 1.27 1.27)
				)
				(justify mirror)
			)
		)
		(property "Value" ""
			(at 0 0 90)
			(layer "B.Fab")
			(effects
				(font
					(size 1.27 1.27)
				)
				(justify mirror)
			)
		)
		(duplicate_pad_numbers_are_jumpers no)
		(fp_poly
			(pts
				(xy 0.2794 -0.1016) (xy -0.2794 -0.1016) (xy -0.2794 0.9906) (xy 0.2794 0.9906)
			)
			(stroke
				(width 0)
				(type default)
			)
			(fill no)
			(layer "B.CrtYd")
		)
		(fp_line
			(start -0.2794 0.9906)
			(end -0.2794 -0.1016)
			(stroke
				(width 0.1)
				(type default)
			)
			(layer "B.Fab")
		)
		(fp_line
			(start 0.2794 0.9906)
			(end -0.2794 0.9906)
			(stroke
				(width 0.1)
				(type default)
			)
			(layer "B.Fab")
		)
		(fp_line
			(start -0.2794 -0.1016)
			(end 0.2794 -0.1016)
			(stroke
				(width 0.1)
				(type default)
			)
			(layer "B.Fab")
		)
		(fp_line
			(start 0.2794 -0.1016)
			(end 0.2794 0.9906)
			(stroke
				(width 0.1)
				(type default)
			)
			(layer "B.Fab")
		)
		(pad "1" smd rect
			(at 0 0 90)
			(size 0.508 0.508)
			(layers "B.Cu" "B.Mask" "B.Paste")
			(net "A_PCIEUP_RCOMP_P")
		)
		(pad "2" smd rect
			(at 0 0.889 90)
			(size 0.508 0.508)
			(layers "B.Cu" "B.Mask" "B.Paste")
			(net "A_PCIEUP_RCOMP_N")
		)
		(zone
			(layer "B.Cu")
			(hatch none 0.5)
			(connect_pads
				(clearance 0)
			)
			(min_thickness 0.25)
			(keepout
				(tracks not_allowed)
				(vias allowed)
				(pads allowed)
				(copperpour not_allowed)
				(footprints allowed)
			)
			(placement
				(enabled no)
				(sheetname "")
			)
			(fill
				(thermal_gap 0.5)
				(thermal_bridge_width 0.5)
				(island_removal_mode 0)
			)
			(polygon
				(pts
					(xy 387.3754 -125.253242) (xy 387.3754 -125.761242) (xy 387.7564 -125.761242) (xy 387.7564 -125.253242)
				)
			)
		)
		(zone
			(layer "B.Cu")
			(hatch none 0.5)
			(connect_pads
				(clearance 0)
			)
			(min_thickness 0.25)
			(keepout
				(tracks allowed)
				(vias not_allowed)
				(pads allowed)
				(copperpour not_allowed)
				(footprints allowed)
			)
			(placement
				(enabled no)
				(sheetname "")
			)
			(fill
				(thermal_gap 0.5)
				(thermal_bridge_width 0.5)
				(island_removal_mode 0)
			)
			(polygon
				(pts
					(xy 387.7564 -125.253242) (xy 387.7564 -125.761242) (xy 387.3754 -125.761242) (xy 387.3754 -125.253242)
				)
			)
		)
	)
	(footprint ""
		(layer "B.Cu")
		(at 87.158068 -17.7546 -90)
		(property "Reference" "C8T8"
			(at -1.848866 0.752348 270)
			(unlocked yes)
			(layer "B.SilkS")
			(effects
				(font
					(size 1.27 0.9652)
					(thickness 0.1524)
				)
				(justify mirror)
			)
		)
		(property "Value" ""
			(at 0 0 90)
			(layer "B.Fab")
			(effects
				(font
					(size 1.27 1.27)
				)
				(justify mirror)
			)
		)
		(duplicate_pad_numbers_are_jumpers no)
		(fp_rect
			(start 0.500126 1.598422)
			(end -0.500126 -0.201422)
			(stroke
				(width 0)
				(type default)
			)
			(fill no)
			(layer "B.CrtYd")
		)
		(fp_line
			(start -0.500126 1.598422)
			(end 0.500126 1.598422)
			(stroke
				(width 0.1)
				(type default)
			)
			(layer "B.Fab")
		)
		(fp_line
			(start 0.500126 1.598422)
			(end 0.500126 -0.201422)
			(stroke
				(width 0.1)
				(type default)
			)
			(layer "B.Fab")
		)
		(fp_line
			(start -0.500126 -0.201422)
			(end -0.500126 1.598422)
			(stroke
				(width 0.1)
				(type default)
			)
			(layer "B.Fab")
		)
		(fp_line
			(start 0.500126 -0.201422)
			(end -0.500126 -0.201422)
			(stroke
				(width 0.1)
				(type default)
			)
			(layer "B.Fab")
		)
		(pad "1" smd rect
			(at 0 0 180)
			(size 0.889 0.9906)
			(layers "B.Cu" "B.Mask" "B.Paste")
			(net "PVDDQ_GHJ")
		)
		(pad "2" smd rect
			(at 0 1.397 180)
			(size 0.889 0.9906)
			(layers "B.Cu" "B.Mask" "B.Paste")
			(net "GND")
		)
		(zone
			(layer "B.Cu")
			(hatch none 0.5)
			(connect_pads
				(clearance 0)
			)
			(min_thickness 0.25)
			(keepout
				(tracks allowed)
				(vias not_allowed)
				(pads allowed)
				(copperpour not_allowed)
				(footprints allowed)
			)
			(placement
				(enabled no)
				(sheetname "")
			)
			(fill
				(thermal_gap 0.5)
				(thermal_bridge_width 0.5)
				(island_removal_mode 0)
			)
			(polygon
				(pts
					(xy 86.205568 -17.2593) (xy 86.713568 -17.2593) (xy 86.713568 -18.2499) (xy 86.205568 -18.2499)
				)
			)
		)
		(zone
			(layer "B.Cu")
			(hatch none 0.5)
			(connect_pads
				(clearance 0)
			)
			(min_thickness 0.25)
			(keepout
				(tracks not_allowed)
				(vias allowed)
				(pads allowed)
				(copperpour not_allowed)
				(footprints allowed)
			)
			(placement
				(enabled no)
				(sheetname "")
			)
			(fill
				(thermal_gap 0.5)
				(thermal_bridge_width 0.5)
				(island_removal_mode 0)
			)
			(polygon
				(pts
					(xy 86.205568 -17.2593) (xy 86.713568 -17.2593) (xy 86.713568 -18.2499) (xy 86.205568 -18.2499)
				)
			)
		)
	)
	(footprint ""
		(layer "B.Cu")
		(at 413.0675 -26.162 -90)
		(property "Reference" "C25W31"
			(at 0.8382 -0.67818 270)
			(unlocked yes)
			(layer "B.SilkS")
			(effects
				(font
					(size 0.4064 0.254)
					(thickness 0.1524)
				)
				(justify left mirror)
			)
		)
		(property "Value" ""
			(at 0 0 90)
			(layer "B.Fab")
			(effects
				(font
					(size 1.27 1.27)
				)
				(justify mirror)
			)
		)
		(duplicate_pad_numbers_are_jumpers no)
		(fp_poly
			(pts
				(xy -0.3048 -0.1016) (xy -0.3048 0.9906) (xy 0.3048 0.9906) (xy 0.3048 -0.1016)
			)
			(stroke
				(width 0)
				(type default)
			)
			(fill no)
			(layer "B.CrtYd")
		)
		(fp_line
			(start -0.3048 0.9906)
			(end -0.3048 -0.1016)
			(stroke
				(width 0.1)
				(type default)
			)
			(layer "B.Fab")
		)
		(fp_line
			(start 0.3048 0.9906)
			(end -0.3048 0.9906)
			(stroke
				(width 0.1)
				(type default)
			)
			(layer "B.Fab")
		)
		(fp_line
			(start -0.3048 -0.1016)
			(end 0.3048 -0.1016)
			(stroke
				(width 0.1)
				(type default)
			)
			(layer "B.Fab")
		)
		(fp_line
			(start 0.3048 -0.1016)
			(end 0.3048 0.9906)
			(stroke
				(width 0.1)
				(type default)
			)
			(layer "B.Fab")
		)
		(pad "1" smd rect
			(at 0 0 90)
			(size 0.508 0.508)
			(layers "B.Cu" "B.Mask" "B.Paste")
			(net "VCC_ADCAV3V3")
		)
		(pad "2" smd rect
			(at 0 0.889 90)
			(size 0.508 0.508)
			(layers "B.Cu" "B.Mask" "B.Paste")
			(net "GND")
		)
		(zone
			(layer "B.Cu")
			(hatch none 0.5)
			(connect_pads
				(clearance 0)
			)
			(min_thickness 0.25)
			(keepout
				(tracks not_allowed)
				(vias allowed)
				(pads allowed)
				(copperpour not_allowed)
				(footprints allowed)
			)
			(placement
				(enabled no)
				(sheetname "")
			)
			(fill
				(thermal_gap 0.5)
				(thermal_bridge_width 0.5)
				(island_removal_mode 0)
			)
			(polygon
				(pts
					(xy 412.4325 -25.908) (xy 412.4325 -26.416) (xy 412.8135 -26.416) (xy 412.8135 -25.908)
				)
			)
		)
		(zone
			(layer "B.Cu")
			(hatch none 0.5)
			(connect_pads
				(clearance 0)
			)
			(min_thickness 0.25)
			(keepout
				(tracks allowed)
				(vias not_allowed)
				(pads allowed)
				(copperpour not_allowed)
				(footprints allowed)
			)
			(placement
				(enabled no)
				(sheetname "")
			)
			(fill
				(thermal_gap 0.5)
				(thermal_bridge_width 0.5)
				(island_removal_mode 0)
			)
			(polygon
				(pts
					(xy 412.8135 -25.908) (xy 412.8135 -26.416) (xy 412.4325 -26.416) (xy 412.4325 -25.908)
				)
			)
		)
	)
	(footprint ""
		(layer "B.Cu")
		(at 253.392432 -17.7546 90)
		(property "Reference" "C5T9"
			(at -1.848866 0.752348 90)
			(unlocked yes)
			(layer "B.SilkS")
			(effects
				(font
					(size 1.27 0.9652)
					(thickness 0.1524)
				)
				(justify mirror)
			)
		)
		(property "Value" ""
			(at 0 0 90)
			(layer "B.Fab")
			(effects
				(font
					(size 1.27 1.27)
				)
				(justify mirror)
			)
		)
		(duplicate_pad_numbers_are_jumpers no)
		(fp_rect
			(start 0.500126 1.598422)
			(end -0.500126 -0.201422)
			(stroke
				(width 0)
				(type default)
			)
			(fill no)
			(layer "B.CrtYd")
		)
		(fp_line
			(start 0.500126 -0.201422)
			(end -0.500126 -0.201422)
			(stroke
				(width 0.1)
				(type default)
			)
			(layer "B.Fab")
		)
		(fp_line
			(start -0.500126 -0.201422)
			(end -0.500126 1.598422)
			(stroke
				(width 0.1)
				(type default)
			)
			(layer "B.Fab")
		)
		(fp_line
			(start 0.500126 1.598422)
			(end 0.500126 -0.201422)
			(stroke
				(width 0.1)
				(type default)
			)
			(layer "B.Fab")
		)
		(fp_line
			(start -0.500126 1.598422)
			(end 0.500126 1.598422)
			(stroke
				(width 0.1)
				(type default)
			)
			(layer "B.Fab")
		)
		(pad "1" smd rect
			(at 0 0)
			(size 0.889 0.9906)
			(layers "B.Cu" "B.Mask" "B.Paste")
			(net "PVDDQ_ABC")
		)
		(pad "2" smd rect
			(at 0 1.397)
			(size 0.889 0.9906)
			(layers "B.Cu" "B.Mask" "B.Paste")
			(net "GND")
		)
		(zone
			(layer "B.Cu")
			(hatch none 0.5)
			(connect_pads
				(clearance 0)
			)
			(min_thickness 0.25)
			(keepout
				(tracks allowed)
				(vias not_allowed)
				(pads allowed)
				(copperpour not_allowed)
				(footprints allowed)
			)
			(placement
				(enabled no)
				(sheetname "")
			)
			(fill
				(thermal_gap 0.5)
				(thermal_bridge_width 0.5)
				(island_removal_mode 0)
			)
			(polygon
				(pts
					(xy 254.344932 -18.2499) (xy 253.836932 -18.2499) (xy 253.836932 -17.2593) (xy 254.344932 -17.2593)
				)
			)
		)
		(zone
			(layer "B.Cu")
			(hatch none 0.5)
			(connect_pads
				(clearance 0)
			)
			(min_thickness 0.25)
			(keepout
				(tracks not_allowed)
				(vias allowed)
				(pads allowed)
				(copperpour not_allowed)
				(footprints allowed)
			)
			(placement
				(enabled no)
				(sheetname "")
			)
			(fill
				(thermal_gap 0.5)
				(thermal_bridge_width 0.5)
				(island_removal_mode 0)
			)
			(polygon
				(pts
					(xy 254.344932 -18.2499) (xy 253.836932 -18.2499) (xy 253.836932 -17.2593) (xy 254.344932 -17.2593)
				)
			)
		)
	)
)
